#ISCELL
  pure_quanta quanta_title_block_c *
  *
#CELL
  pure_quanta socket4677_azif0045p001c01cs *
  page20_i1
#ISCELL
  standard tap *
  page20_i10
#ISCELL
  standard tap *
  page20_i100
#ISCELL
  standard tap *
  page20_i101
#ISCELL
  standard tap *
  page20_i102
#ISCELL
  standard tap *
  page20_i103
#ISCELL
  standard tap *
  page20_i104
#ISCELL
  standard offpage *
  page20_i105
#ISCELL
  standard tap *
  page20_i106
#ISCELL
  standard tap *
  page20_i107
#ISCELL
  standard tap *
  page20_i108
#ISCELL
  standard offpage *
  page20_i109
#ISCELL
  standard tap *
  page20_i11
#ISCELL
  standard tap *
  page20_i110
#ISCELL
  standard tap *
  page20_i111
#ISCELL
  standard tap *
  page20_i112
#ISCELL
  standard tap *
  page20_i113
#ISCELL
  standard tap *
  page20_i114
#ISCELL
  standard tap *
  page20_i115
#ISCELL
  standard tap *
  page20_i116
#ISCELL
  standard tap *
  page20_i117
#ISCELL
  standard tap *
  page20_i118
#ISCELL
  standard tap *
  page20_i119
#ISCELL
  standard tap *
  page20_i12
#ISCELL
  standard tap *
  page20_i120
#ISCELL
  standard tap *
  page20_i121
#ISCELL
  standard tap *
  page20_i122
#ISCELL
  standard tap *
  page20_i123
#ISCELL
  standard tap *
  page20_i124
#ISCELL
  standard tap *
  page20_i125
#ISCELL
  standard tap *
  page20_i126
#ISCELL
  standard tap *
  page20_i127
#ISCELL
  standard tap *
  page20_i128
#ISCELL
  standard tap *
  page20_i129
#ISCELL
  standard tap *
  page20_i13
#ISCELL
  standard tap *
  page20_i130
#ISCELL
  standard tap *
  page20_i131
#ISCELL
  standard tap *
  page20_i132
#ISCELL
  standard tap *
  page20_i133
#ISCELL
  standard offpage *
  page20_i134
#ISCELL
  standard offpage *
  page20_i135
#ISCELL
  standard offpage *
  page20_i136
#ISCELL
  standard offpage *
  page20_i137
#ISCELL
  standard tap *
  page20_i138
#ISCELL
  standard tap *
  page20_i139
#ISCELL
  standard tap *
  page20_i14
#ISCELL
  standard tap *
  page20_i140
#ISCELL
  standard tap *
  page20_i141
#ISCELL
  standard tap *
  page20_i142
#ISCELL
  standard tap *
  page20_i143
#ISCELL
  standard tap *
  page20_i144
#ISCELL
  standard tap *
  page20_i147
#ISCELL
  standard tap *
  page20_i148
#ISCELL
  standard tap *
  page20_i149
#ISCELL
  standard tap *
  page20_i15
#ISCELL
  standard tap *
  page20_i150
#ISCELL
  standard offpage *
  page20_i151
#ISCELL
  standard offpage *
  page20_i152
#ISCELL
  standard tap *
  page20_i153
#ISCELL
  standard tap *
  page20_i154
#ISCELL
  standard tap *
  page20_i155
#ISCELL
  standard tap *
  page20_i156
#ISCELL
  standard offpage *
  page20_i157
#ISCELL
  standard offpage *
  page20_i158
#ISCELL
  standard offpage *
  page20_i159
#ISCELL
  standard tap *
  page20_i16
#ISCELL
  standard offpage *
  page20_i160
#ISCELL
  standard offpage *
  page20_i161
#ISCELL
  standard tap *
  page20_i162
#ISCELL
  standard tap *
  page20_i163
#ISCELL
  standard tap *
  page20_i164
#ISCELL
  standard tap *
  page20_i165
#ISCELL
  standard tap *
  page20_i166
#ISCELL
  standard tap *
  page20_i167
#ISCELL
  standard tap *
  page20_i168
#ISCELL
  standard tap *
  page20_i169
#ISCELL
  standard tap *
  page20_i17
#ISCELL
  standard offpage *
  page20_i170
#ISCELL
  standard tap *
  page20_i171
#ISCELL
  standard tap *
  page20_i172
#ISCELL
  standard tap *
  page20_i175
#ISCELL
  standard tap *
  page20_i176
#ISCELL
  standard offpage *
  page20_i177
#ISCELL
  standard offpage *
  page20_i178
#ISCELL
  standard tap *
  page20_i18
#ISCELL
  standard tap *
  page20_i19
#ISCELL
  standard offpage *
  page20_i2
#ISCELL
  standard tap *
  page20_i20
#ISCELL
  standard tap *
  page20_i21
#ISCELL
  standard tap *
  page20_i22
#ISCELL
  standard tap *
  page20_i23
#ISCELL
  standard tap *
  page20_i24
#ISCELL
  standard tap *
  page20_i25
#ISCELL
  standard tap *
  page20_i26
#ISCELL
  standard tap *
  page20_i27
#ISCELL
  standard tap *
  page20_i28
#ISCELL
  standard tap *
  page20_i29
#ISCELL
  standard tap *
  page20_i3
#ISCELL
  standard tap *
  page20_i30
#ISCELL
  standard tap *
  page20_i31
#ISCELL
  standard tap *
  page20_i32
#ISCELL
  standard tap *
  page20_i33
#ISCELL
  standard tap *
  page20_i34
#ISCELL
  standard tap *
  page20_i35
#ISCELL
  standard tap *
  page20_i36
#ISCELL
  standard tap *
  page20_i37
#ISCELL
  standard offpage *
  page20_i38
#ISCELL
  standard tap *
  page20_i39
#ISCELL
  standard tap *
  page20_i4
#ISCELL
  standard tap *
  page20_i40
#ISCELL
  standard tap *
  page20_i41
#ISCELL
  standard tap *
  page20_i42
#ISCELL
  standard tap *
  page20_i43
#ISCELL
  standard tap *
  page20_i44
#ISCELL
  standard tap *
  page20_i45
#ISCELL
  standard tap *
  page20_i46
#ISCELL
  standard tap *
  page20_i47
#ISCELL
  standard tap *
  page20_i48
#ISCELL
  standard tap *
  page20_i49
#ISCELL
  standard tap *
  page20_i5
#ISCELL
  standard tap *
  page20_i50
#ISCELL
  standard tap *
  page20_i51
#ISCELL
  standard tap *
  page20_i52
#ISCELL
  standard tap *
  page20_i53
#ISCELL
  standard tap *
  page20_i54
#ISCELL
  standard tap *
  page20_i55
#ISCELL
  standard tap *
  page20_i56
#ISCELL
  standard tap *
  page20_i57
#ISCELL
  standard tap *
  page20_i58
#ISCELL
  standard tap *
  page20_i59
#ISCELL
  standard tap *
  page20_i6
#ISCELL
  standard tap *
  page20_i60
#ISCELL
  standard tap *
  page20_i61
#ISCELL
  standard tap *
  page20_i62
#ISCELL
  standard tap *
  page20_i63
#ISCELL
  standard tap *
  page20_i64
#ISCELL
  standard tap *
  page20_i65
#ISCELL
  standard tap *
  page20_i66
#ISCELL
  standard tap *
  page20_i67
#ISCELL
  standard tap *
  page20_i68
#ISCELL
  standard tap *
  page20_i69
#ISCELL
  standard tap *
  page20_i7
#ISCELL
  standard tap *
  page20_i70
#ISCELL
  standard tap *
  page20_i71
#ISCELL
  standard tap *
  page20_i72
#ISCELL
  standard tap *
  page20_i73
#ISCELL
  standard offpage *
  page20_i74
#ISCELL
  standard tap *
  page20_i75
#ISCELL
  standard tap *
  page20_i76
#ISCELL
  standard tap *
  page20_i8
#ISCELL
  standard tap *
  page20_i82
#ISCELL
  standard tap *
  page20_i84
#ISCELL
  standard tap *
  page20_i85
#ISCELL
  standard tap *
  page20_i86
#ISCELL
  standard tap *
  page20_i87
#ISCELL
  standard tap *
  page20_i88
#ISCELL
  standard tap *
  page20_i89
#ISCELL
  standard tap *
  page20_i9
#ISCELL
  standard tap *
  page20_i90
#ISCELL
  standard tap *
  page20_i91
#ISCELL
  standard tap *
  page20_i92
#ISCELL
  standard offpage *
  page20_i93
#ISCELL
  standard tap *
  page20_i94
#ISCELL
  standard offpage *
  page20_i95
#ISCELL
  standard tap *
  page20_i96
#ISCELL
  standard tap *
  page20_i97
#ISCELL
  standard tap *
  page20_i98
#ISCELL
  standard tap *
  page20_i99
